# S9S_MB_2U (Grand Teton) — schematic netlist excerpt (pin names and nets, part order shuffled) for the footprints in the layout excerpt that follows; sources: Cadence DE-HDL packaged netlist, KiCad conversion of 03242023_DA0F0TMBIJ0_F0T_Motherboard_J_brd_V01_OCP.brd

U145  74LVC1G126SE7  74LVC1G126SE-7 IC  pkg SOT353_0-65_2X1-25  page 191
  OE  = FM_PS_EN_PLD_BUF1_R1
  A  = E1S_0_PRSNT
  GND  = GND
  Y  = E1S_0_EN
  VCC  = P3V3_AUX

R4170  Q_RES  33.2 1% CHIP  pkg 0402LF  page 215 : A = GPU_3V3IO_RSVD1_ISO ; B = GPU_3V3IO_RSVD1_ISO_R
C837  Q_CAP_DIFFBUS  DIFF BUS_0.22UF 6.3V 20% X6S  pkg C0201  page 175 : \1\ = P5E_CPU1_PE1_TX_C_DP<0> ; \2\ = P5E_CPU1_PE1_TX_DP<0>

(kicad_pcb
	(version 20260206)
	(generator "pcbnew")
	(generator_version "10.0")
	(general
		(thickness 1.6)
		(legacy_teardrops no)
	)
	(paper "A4")
	(title_block
		(title "03242023_DA0F0TMBIJ0_F0T_Motherboard_J_brd_V01_OCP.brd")
		(comment 1 "Grand Teton / footprints 1862-1864 of 6105")
	)
	(layers
		(0 "F.Cu" signal "TOP")
		(4 "In1.Cu" signal "GND")
		(6 "In2.Cu" signal "IN1")
		(8 "In3.Cu" signal "GND1")
		(10 "In4.Cu" signal "IN2")
		(12 "In5.Cu" signal "GND2")
		(14 "In6.Cu" signal "IN3")
		(16 "In7.Cu" signal "GND3")
		(18 "In8.Cu" signal "VCC")
		(20 "In9.Cu" signal "VCC1")
		(22 "In10.Cu" signal "GND4")
		(24 "In11.Cu" signal "IN4")
		(26 "In12.Cu" signal "GND5")
		(28 "In13.Cu" signal "IN5")
		(30 "In14.Cu" signal "GND6")
		(32 "In15.Cu" signal "IN6")
		(34 "In16.Cu" signal "GND7")
		(2 "B.Cu" signal "BOTTOM")
		(9 "F.Adhes" user "F.Adhesive")
		(11 "B.Adhes" user "B.Adhesive")
		(13 "F.Paste" user "Package Geometry/Pastemask Top")
		(15 "B.Paste" user "Package Geometry/Pastemask Bottom")
		(5 "F.SilkS" user "Ref Des/Silkscreen Top")
		(7 "B.SilkS" user "Ref Des/Silkscreen Bottom")
		(1 "F.Mask" user "Board Geometry/Soldermask Top")
		(3 "B.Mask" user "Board Geometry/Soldermask Bottom")
		(17 "Dwgs.User" user "User.Drawings")
		(19 "Cmts.User" user "User.Comments")
		(21 "Eco1.User" user "User.Eco1")
		(23 "Eco2.User" user "User.Eco2")
		(25 "Edge.Cuts" user "Board Geometry/Outline")
		(27 "Margin" user)
		(31 "F.CrtYd" user "Package Geometry/Place Bound Top")
		(29 "B.CrtYd" user "Package Geometry/Place Bound Bottom")
		(35 "F.Fab" user "Ref Des/Assembly Top")
		(33 "B.Fab" user "Ref Des/Assembly Bottom")
	)
	(footprint ""
		(layer "F.Cu")
		(at 145.131536 -64.701928)
		(property "Reference" "U145"
			(at -1.47066 2.016252 0)
			(unlocked yes)
			(layer "F.SilkS")
			(effects
				(font
					(size 0.7874 0.5842)
					(thickness 0.1524)
				)
				(justify left)
			)
		)
		(property "Value" ""
			(at 0 0 0)
			(layer "F.Fab")
			(effects
				(font
					(size 1.27 1.27)
				)
			)
		)
		(duplicate_pad_numbers_are_jumpers no)
		(fp_line
			(start -1.400048 1.100074)
			(end -1.400048 -1.100074)
			(stroke
				(width 0.1524)
				(type default)
			)
			(layer "F.SilkS")
		)
		(fp_line
			(start 1.400048 -1.100074)
			(end -1.400048 -1.100074)
			(stroke
				(width 0.1524)
				(type default)
			)
			(layer "F.SilkS")
		)
		(fp_line
			(start 1.400048 -1.100074)
			(end 1.400048 1.100074)
			(stroke
				(width 0.1524)
				(type default)
			)
			(layer "F.SilkS")
		)
		(fp_line
			(start 1.400048 1.100074)
			(end -1.400048 1.100074)
			(stroke
				(width 0.1524)
				(type default)
			)
			(layer "F.SilkS")
		)
		(fp_poly
			(pts
				(xy -1.05283 -1.437132) (xy -1.56083 -2.453132) (xy -0.54483 -2.453132)
			)
			(stroke
				(width 0)
				(type default)
			)
			(fill yes)
			(layer "F.SilkS")
		)
		(fp_line
			(start -0.674878 -1.100074)
			(end 0.674878 -1.100074)
			(stroke
				(width 0.1)
				(type default)
			)
			(layer "F.Fab")
		)
		(fp_line
			(start -0.674878 1.100074)
			(end -0.674878 -1.100074)
			(stroke
				(width 0.1)
				(type default)
			)
			(layer "F.Fab")
		)
		(fp_line
			(start 0.674878 -1.100074)
			(end 0.674878 1.100074)
			(stroke
				(width 0.1)
				(type default)
			)
			(layer "F.Fab")
		)
		(fp_line
			(start 0.674878 1.100074)
			(end -0.674878 1.100074)
			(stroke
				(width 0.1)
				(type default)
			)
			(layer "F.Fab")
		)
		(fp_poly
			(pts
				(xy -1.590548 -0.649986) (xy -2.606548 -1.157986) (xy -2.606548 -0.141986)
			)
			(stroke
				(width 0)
				(type default)
			)
			(fill yes)
			(layer "F.Fab")
		)
		(pad "1" smd rect
			(at -0.94996 -0.649986 270)
			(size 0.4318 0.6096)
			(layers "F.Cu" "F.Mask" "F.Paste")
			(net "FM_PS_EN_PLD_BUF1_R1")
		)
		(pad "2" smd rect
			(at -0.94996 0 270)
			(size 0.4318 0.6096)
			(layers "F.Cu" "F.Mask" "F.Paste")
			(net "E1S_0_PRSNT")
		)
		(pad "3" smd rect
			(at -0.94996 0.649986 270)
			(size 0.4318 0.6096)
			(layers "F.Cu" "F.Mask" "F.Paste")
			(net "GND")
		)
		(pad "4" smd rect
			(at 0.94996 0.649986 270)
			(size 0.4318 0.6096)
			(layers "F.Cu" "F.Mask" "F.Paste")
			(net "E1S_0_EN")
		)
		(pad "5" smd rect
			(at 0.94996 -0.649986 270)
			(size 0.4318 0.6096)
			(layers "F.Cu" "F.Mask" "F.Paste")
			(net "P3V3_AUX")
		)
	)
	(footprint ""
		(layer "F.Cu")
		(at 58.67273 -17.623536 90)
		(property "Reference" "C837"
			(at 0 0 90)
			(layer "F.SilkS")
			(hide yes)
			(effects
				(font
					(size 1.27 1.27)
				)
			)
		)
		(property "Value" ""
			(at 0 0 90)
			(layer "F.Fab")
			(effects
				(font
					(size 1.27 1.27)
				)
			)
		)
		(duplicate_pad_numbers_are_jumpers no)
		(fp_line
			(start 0.299974 -0.150114)
			(end 0.299974 0.150114)
			(stroke
				(width 0.1)
				(type default)
			)
			(layer "F.Fab")
		)
		(fp_line
			(start -0.299974 -0.150114)
			(end 0.299974 -0.150114)
			(stroke
				(width 0.1)
				(type default)
			)
			(layer "F.Fab")
		)
		(fp_line
			(start 0.299974 0.150114)
			(end -0.299974 0.150114)
			(stroke
				(width 0.1)
				(type default)
			)
			(layer "F.Fab")
		)
		(fp_line
			(start -0.299974 0.150114)
			(end -0.299974 -0.150114)
			(stroke
				(width 0.1)
				(type default)
			)
			(layer "F.Fab")
		)
		(pad "1" smd rect
			(at -0.2667 0 90)
			(size 0.3048 0.381)
			(layers "F.Cu" "F.Mask" "F.Paste")
			(net "P5E_CPU1_PE1_TX_C_DP<0>")
		)
		(pad "2" smd rect
			(at 0.2667 0 90)
			(size 0.3048 0.381)
			(layers "F.Cu" "F.Mask" "F.Paste")
			(net "P5E_CPU1_PE1_TX_DP<0>")
		)
	)
	(footprint ""
		(layer "F.Cu")
		(at 208.49336 -118.074948 180)
		(property "Reference" "R4170"
			(at 0 0 180)
			(layer "F.SilkS")
			(hide yes)
			(effects
				(font
					(size 1.27 1.27)
				)
			)
		)
		(property "Value" ""
			(at 0 0 180)
			(layer "F.Fab")
			(effects
				(font
					(size 1.27 1.27)
				)
			)
		)
		(duplicate_pad_numbers_are_jumpers no)
		(fp_line
			(start 0.7874 0.4064)
			(end -0.7874 0.4064)
			(stroke
				(width 0.1524)
				(type default)
			)
			(layer "F.SilkS")
		)
		(fp_line
			(start 0.7874 -0.4064)
			(end 0.7874 0.4064)
			(stroke
				(width 0.1524)
				(type default)
			)
			(layer "F.SilkS")
		)
		(fp_line
			(start -0.7874 0.4064)
			(end -0.7874 -0.4064)
			(stroke
				(width 0.1524)
				(type default)
			)
			(layer "F.SilkS")
		)
		(fp_line
			(start -0.7874 -0.4064)
			(end 0.7874 -0.4064)
			(stroke
				(width 0.1524)
				(type default)
			)
			(layer "F.SilkS")
		)
		(fp_line
			(start 0.67945 0.3048)
			(end 0.120396 0.3048)
			(stroke
				(width 0.1)
				(type default)
			)
			(layer "F.Fab")
		)
		(fp_line
			(start 0.67945 -0.3048)
			(end 0.67945 0.3048)
			(stroke
				(width 0.1)
				(type default)
			)
			(layer "F.Fab")
		)
		(fp_line
			(start 0.12065 -0.2794)
			(end 0.12065 -0.3048)
			(stroke
				(width 0.1)
				(type default)
			)
			(layer "F.Fab")
		)
		(fp_line
			(start 0.12065 -0.3048)
			(end 0.67945 -0.3048)
			(stroke
				(width 0.1)
				(type default)
			)
			(layer "F.Fab")
		)
		(fp_line
			(start 0.120396 0.3048)
			(end 0.120396 0.2794)
			(stroke
				(width 0.1)
				(type default)
			)
			(layer "F.Fab")
		)
		(fp_line
			(start 0.120396 0.2794)
			(end -0.12065 0.2794)
			(stroke
				(width 0.1)
				(type default)
			)
			(layer "F.Fab")
		)
		(fp_line
			(start -0.12065 0.3048)
			(end -0.67945 0.3048)
			(stroke
				(width 0.1)
				(type default)
			)
			(layer "F.Fab")
		)
		(fp_line
			(start -0.12065 0.2794)
			(end -0.12065 0.3048)
			(stroke
				(width 0.1)
				(type default)
			)
			(layer "F.Fab")
		)
		(fp_line
			(start -0.12065 -0.2794)
			(end 0.12065 -0.2794)
			(stroke
				(width 0.1)
				(type default)
			)
			(layer "F.Fab")
		)
		(fp_line
			(start -0.12065 -0.305054)
			(end -0.12065 -0.2794)
			(stroke
				(width 0.1)
				(type default)
			)
			(layer "F.Fab")
		)
		(fp_line
			(start -0.67945 0.3048)
			(end -0.67945 -0.305054)
			(stroke
				(width 0.1)
				(type default)
			)
			(layer "F.Fab")
		)
		(fp_line
			(start -0.67945 -0.305054)
			(end -0.12065 -0.305054)
			(stroke
				(width 0.1)
				(type default)
			)
			(layer "F.Fab")
		)
		(pad "1" smd circle
			(at -0.40005 0 180)
			(size 0 0)
			(layers "F.Cu" "F.Mask" "F.Paste")
			(net "GPU_3V3IO_RSVD1_ISO")
		)
		(pad "2" smd circle
			(at 0.40005 0 180)
			(size 0 0)
			(layers "F.Cu" "F.Mask" "F.Paste")
			(net "GPU_3V3IO_RSVD1_ISO_R")
		)
	)
)
